#ISCELL
  mstr_symbols intel_corp_bpage *
  *
#ISCELL
  mstr_standard offpage *
  page168_i1
#CELL
  mstr_discrete res *
  page168_i11
#ISCELL
  mstr_symbols gnd *
  page168_i14
#CELL
  mstr_discrete fet_n_dual *
  page168_i18
#CELL
  mstr_discrete fet_n_dual *
  page168_i19
#CELL
  mstr_discrete diode *
  page168_i2
#CELL
  mstr_discrete res *
  page168_i22
#ISCELL
  mstr_symbols p3v3_stby *
  page168_i24
#ISCELL
  mstr_symbols gnd *
  page168_i26
#ISCELL
  mstr_standard offpage *
  page168_i28
#ISCELL
  mstr_symbols p3v3_stby *
  page168_i29
#CELL
  mstr_discrete diode *
  page168_i3
#ISCELL
  mstr_standard offpage *
  page168_i31
#ISCELL
  mstr_symbols gnd *
  page168_i36
#ISCELL
  mstr_symbols p3v3_stby *
  page168_i38
#CELL
  mstr_discrete diode *
  page168_i4
#CELL
  mstr_discrete fet_n *
  page168_i43
#ISCELL
  mstr_symbols gnd *
  page168_i44
#ISCELL
  mstr_standard offpage *
  page168_i45
#CELL
  mstr_discrete res *
  page168_i46
#CELL
  mstr_discrete npn *
  page168_i47
#CELL
  mstr_discrete res *
  page168_i48
#CELL
  mstr_discrete diode *
  page168_i5
#CELL
  mstr_discrete res *
  page168_i6
#CELL
  mstr_discrete npn *
  page168_i8
